# T6G (Grand Teton) — schematic netlist excerpt (pin names and nets, part order shuffled) for the footprints in the layout excerpt that follows; sources: Cadence DE-HDL packaged netlist, KiCad conversion of 04192023_DAF0TMB3IC0_F0TG_MB_C_brd_V02_OCP.brd

PU292  RS31312R  IC  pkg QFN22_TH_3X5  page 147
  EN  = P12V_E1S_EN_0_R2
  LOADEN  = GND
  ENTM  = GND
  TIMER  = P12V_E1S_TIMER_0
  ISET  = P12V_E1S_ISET_0
  SS  = P12V_E1S_SS_0
  GND  = GND
  IMON  = P12V_E1S_IMON_0
  FLTB  = P12V_E1S_FLTB_0
  PG  = HP_LVC3_E1S_0_HSC_PWRGD
  OV  = P12V_E1S_OV_FB_0
  AVIN  = P12V_E1S_AVIN_PD_0
  VOUT_13  = P12V_E1S_0
  VOUT_14  = P12V_E1S_0
  VOUT_15  = P12V_E1S_0
  VOUT_16  = P12V_E1S_0
  VOUT_17  = P12V_E1S_0
  VOUT_18  = P12V_E1S_0
  VOUT_19  = P12V_E1S_0
  VOUT_20  = P12V_E1S_0
  VIN_21_22  = P12V_AUX
  VIN_23  = P12V_AUX
  VIN_24  = P12V_AUX
  VIN_25  = P12V_AUX
  VIN_26  = P12V_AUX

(kicad_pcb
	(version 20260206)
	(generator "pcbnew")
	(generator_version "10.0")
	(general
		(thickness 1.6)
		(legacy_teardrops no)
	)
	(paper "A4")
	(title_block
		(title "04192023_DAF0TMB3IC0_F0TG_MB_C_brd_V02_OCP.brd")
		(comment 1 "Grand Teton / footprint 2579 of 8354 (PU292), pads 1-25 of 25")
	)
	(layers
		(0 "F.Cu" signal "TOP")
		(4 "In1.Cu" signal "GND")
		(6 "In2.Cu" signal "IN1")
		(8 "In3.Cu" signal "GND1")
		(10 "In4.Cu" signal "IN2")
		(12 "In5.Cu" signal "GND2")
		(14 "In6.Cu" signal "IN3")
		(16 "In7.Cu" signal "GND3")
		(18 "In8.Cu" signal "VCC")
		(20 "In9.Cu" signal "VCC1")
		(22 "In10.Cu" signal "GND4")
		(24 "In11.Cu" signal "IN4")
		(26 "In12.Cu" signal "GND5")
		(28 "In13.Cu" signal "IN5")
		(30 "In14.Cu" signal "GND6")
		(32 "In15.Cu" signal "IN6")
		(34 "In16.Cu" signal "GND7")
		(2 "B.Cu" signal "BOTTOM")
		(9 "F.Adhes" user "F.Adhesive")
		(11 "B.Adhes" user "B.Adhesive")
		(13 "F.Paste" user "Package Geometry/Pastemask Top")
		(15 "B.Paste" user "Package Geometry/Pastemask Bottom")
		(5 "F.SilkS" user "Ref Des/Silkscreen Top")
		(7 "B.SilkS" user "Ref Des/Silkscreen Bottom")
		(1 "F.Mask" user "Board Geometry/Soldermask Top")
		(3 "B.Mask" user "Board Geometry/Soldermask Bottom")
		(17 "Dwgs.User" user "User.Drawings")
		(19 "Cmts.User" user "User.Comments")
		(21 "Eco1.User" user "User.Eco1")
		(23 "Eco2.User" user "User.Eco2")
		(25 "Edge.Cuts" user "Board Geometry/Outline")
		(27 "Margin" user)
		(31 "F.CrtYd" user "Package Geometry/Place Bound Top")
		(29 "B.CrtYd" user "Package Geometry/Place Bound Bottom")
		(35 "F.Fab" user "Ref Des/Assembly Top")
		(33 "B.Fab" user "Ref Des/Assembly Bottom")
	)
	(footprint ""
		(layer "F.Cu")
		(at 253.86157 -51.382422 180)
		(property "Reference" "PU292"
			(at -1.008634 -4.773422 0)
			(unlocked yes)
			(layer "F.SilkS")
			(effects
				(font
					(size 0.7874 0.5842)
					(thickness 0.1524)
				)
				(justify left)
			)
		)
		(property "Value" ""
			(at 0 0 180)
			(layer "F.Fab")
			(effects
				(font
					(size 1.27 1.27)
				)
			)
		)
		(duplicate_pad_numbers_are_jumpers no)
		(pad "1" smd circle
			(at -1.374902 -1.999996 90)
			(size 0 0)
			(layers "F.Cu" "F.Mask" "F.Paste")
			(net "P12V_E1S_EN_0_R2")
		)
		(pad "2" smd rect
			(at -1.400048 -1.500124 90)
			(size 0.254 0.8128)
			(layers "F.Cu" "F.Mask" "F.Paste")
			(net "GND")
		)
		(pad "3" smd rect
			(at -1.400048 -0.999998 90)
			(size 0.254 0.8128)
			(layers "F.Cu" "F.Mask" "F.Paste")
			(net "GND")
		)
		(pad "4" smd rect
			(at -1.400048 -0.499872 90)
			(size 0.254 0.8128)
			(layers "F.Cu" "F.Mask" "F.Paste")
			(net "P12V_E1S_TIMER_0")
		)
		(pad "5" smd rect
			(at -1.400048 0 90)
			(size 0.254 0.8128)
			(layers "F.Cu" "F.Mask" "F.Paste")
			(net "P12V_E1S_ISET_0")
		)
		(pad "6" smd rect
			(at -1.400048 0.499872 90)
			(size 0.254 0.8128)
			(layers "F.Cu" "F.Mask" "F.Paste")
			(net "P12V_E1S_SS_0")
		)
		(pad "7" smd rect
			(at -1.400048 0.999998 90)
			(size 0.254 0.8128)
			(layers "F.Cu" "F.Mask" "F.Paste")
			(net "GND")
		)
		(pad "8" smd rect
			(at -1.400048 1.500124 90)
			(size 0.254 0.8128)
			(layers "F.Cu" "F.Mask" "F.Paste")
			(net "P12V_E1S_IMON_0")
		)
		(pad "9" smd rect
			(at -1.400048 1.999996 90)
			(size 0.254 0.8128)
			(layers "F.Cu" "F.Mask" "F.Paste")
			(net "P12V_E1S_FLTB_0")
		)
		(pad "10" smd rect
			(at -0.499872 2.400046 180)
			(size 0.254 0.8128)
			(layers "F.Cu" "F.Mask" "F.Paste")
			(net "HP_LVC3_E1S_0_HSC_PWRGD")
		)
		(pad "11" smd rect
			(at 0.499872 2.400046 180)
			(size 0.254 0.8128)
			(layers "F.Cu" "F.Mask" "F.Paste")
			(net "P12V_E1S_OV_FB_0")
		)
		(pad "12" smd rect
			(at 1.400048 1.999996 90)
			(size 0.254 0.8128)
			(layers "F.Cu" "F.Mask" "F.Paste")
			(net "P12V_E1S_AVIN_PD_0")
		)
		(pad "13" smd rect
			(at 1.400048 1.500124 90)
			(size 0.254 0.8128)
			(layers "F.Cu" "F.Mask" "F.Paste")
			(net "P12V_E1S_0")
		)
		(pad "14" smd rect
			(at 1.400048 0.999998 90)
			(size 0.254 0.8128)
			(layers "F.Cu" "F.Mask" "F.Paste")
			(net "P12V_E1S_0")
		)
		(pad "15" smd rect
			(at 1.400048 0.499872 90)
			(size 0.254 0.8128)
			(layers "F.Cu" "F.Mask" "F.Paste")
			(net "P12V_E1S_0")
		)
		(pad "16" smd rect
			(at 1.400048 0 90)
			(size 0.254 0.8128)
			(layers "F.Cu" "F.Mask" "F.Paste")
			(net "P12V_E1S_0")
		)
		(pad "17" smd rect
			(at 1.400048 -0.499872 90)
			(size 0.254 0.8128)
			(layers "F.Cu" "F.Mask" "F.Paste")
			(net "P12V_E1S_0")
		)
		(pad "18" smd rect
			(at 1.400048 -0.999998 90)
			(size 0.254 0.8128)
			(layers "F.Cu" "F.Mask" "F.Paste")
			(net "P12V_E1S_0")
		)
		(pad "19" smd rect
			(at 1.400048 -1.500124 90)
			(size 0.254 0.8128)
			(layers "F.Cu" "F.Mask" "F.Paste")
			(net "P12V_E1S_0")
		)
		(pad "20" smd rect
			(at 1.400048 -1.999996 90)
			(size 0.254 0.8128)
			(layers "F.Cu" "F.Mask" "F.Paste")
			(net "P12V_E1S_0")
		)
		(pad "21_22" smd circle
			(at 0.499872 -2.337562 90)
			(size 0 0)
			(layers "F.Cu" "F.Mask" "F.Paste")
			(net "P12V_AUX")
		)
		(pad "23" smd rect
			(at 0 -1.100074 90)
			(size 0.254 1.27)
			(layers "F.Cu" "F.Mask" "F.Paste")
			(net "P12V_AUX")
		)
		(pad "24" smd rect
			(at 0 -0.199898 90)
			(size 0.254 1.27)
			(layers "F.Cu" "F.Mask" "F.Paste")
			(net "P12V_AUX")
		)
		(pad "25" smd rect
			(at 0 0.700024 90)
			(size 0.254 1.27)
			(layers "F.Cu" "F.Mask" "F.Paste")
			(net "P12V_AUX")
		)
		(pad "26" smd rect
			(at 0 1.599946 90)
			(size 0.254 1.27)
			(layers "F.Cu" "F.Mask" "F.Paste")
			(net "P12V_AUX")
		)
	)
)
